#ISCELL
  logical_power design_note *
  *
#ISCELL
  pure_quanta quanta_title_block_c *
  *
#ISCELL
  standard offpage *
  page34_i100
#ISCELL
  standard offpage *
  page34_i101
#CELL
  pure_quanta socket4677_azif0045p001c01cs *
  page34_i102
#ISCELL
  standard tap *
  page34_i103
#ISCELL
  standard tap *
  page34_i105
#ISCELL
  standard tap *
  page34_i106
#ISCELL
  standard tap *
  page34_i107
#ISCELL
  standard tap *
  page34_i108
#ISCELL
  standard tap *
  page34_i109
#ISCELL
  standard tap *
  page34_i110
#ISCELL
  standard tap *
  page34_i111
#ISCELL
  standard tap *
  page34_i112
#ISCELL
  standard tap *
  page34_i113
#ISCELL
  standard tap *
  page34_i114
#ISCELL
  standard tap *
  page34_i115
#ISCELL
  standard tap *
  page34_i116
#ISCELL
  standard tap *
  page34_i118
#ISCELL
  standard tap *
  page34_i119
#ISCELL
  standard tap *
  page34_i120
#ISCELL
  standard tap *
  page34_i121
#ISCELL
  standard tap *
  page34_i122
#ISCELL
  standard tap *
  page34_i123
#ISCELL
  standard tap *
  page34_i124
#ISCELL
  standard tap *
  page34_i125
#ISCELL
  standard tap *
  page34_i126
#ISCELL
  standard tap *
  page34_i127
#ISCELL
  standard tap *
  page34_i128
#ISCELL
  standard offpage *
  page34_i129
#ISCELL
  standard tap *
  page34_i130
#ISCELL
  standard tap *
  page34_i131
#ISCELL
  standard tap *
  page34_i14
#ISCELL
  standard tap *
  page34_i16
#ISCELL
  standard tap *
  page34_i17
#ISCELL
  standard offpage *
  page34_i2
#ISCELL
  standard tap *
  page34_i20
#ISCELL
  standard tap *
  page34_i22
#ISCELL
  standard tap *
  page34_i26
#ISCELL
  standard tap *
  page34_i28
#ISCELL
  standard tap *
  page34_i31
#ISCELL
  standard tap *
  page34_i32
#ISCELL
  standard tap *
  page34_i33
#ISCELL
  standard tap *
  page34_i34
#ISCELL
  standard tap *
  page34_i38
#ISCELL
  standard tap *
  page34_i41
#ISCELL
  standard tap *
  page34_i42
#ISCELL
  standard tap *
  page34_i45
#ISCELL
  standard tap *
  page34_i46
#ISCELL
  standard tap *
  page34_i5
#ISCELL
  standard tap *
  page34_i50
#ISCELL
  standard tap *
  page34_i52
#ISCELL
  standard tap *
  page34_i53
#ISCELL
  standard tap *
  page34_i54
#ISCELL
  standard tap *
  page34_i55
#ISCELL
  standard tap *
  page34_i56
#ISCELL
  standard tap *
  page34_i57
#ISCELL
  standard tap *
  page34_i58
#ISCELL
  standard tap *
  page34_i59
#ISCELL
  standard tap *
  page34_i6
#ISCELL
  standard tap *
  page34_i60
#ISCELL
  standard tap *
  page34_i61
#ISCELL
  standard tap *
  page34_i62
#ISCELL
  standard tap *
  page34_i63
#ISCELL
  standard tap *
  page34_i64
#ISCELL
  standard tap *
  page34_i65
#ISCELL
  standard tap *
  page34_i66
#ISCELL
  standard tap *
  page34_i67
#ISCELL
  standard tap *
  page34_i68
#ISCELL
  standard tap *
  page34_i69
#ISCELL
  standard tap *
  page34_i7
#ISCELL
  standard tap *
  page34_i70
#ISCELL
  standard tap *
  page34_i71
#ISCELL
  standard tap *
  page34_i72
#ISCELL
  standard tap *
  page34_i73
#ISCELL
  standard tap *
  page34_i74
#ISCELL
  standard tap *
  page34_i75
#ISCELL
  standard tap *
  page34_i76
#ISCELL
  standard tap *
  page34_i77
#ISCELL
  standard tap *
  page34_i78
#ISCELL
  standard tap *
  page34_i79
#ISCELL
  standard tap *
  page34_i8
#ISCELL
  standard tap *
  page34_i80
#ISCELL
  standard tap *
  page34_i81
#ISCELL
  standard tap *
  page34_i82
#ISCELL
  standard tap *
  page34_i83
#ISCELL
  standard tap *
  page34_i84
#ISCELL
  standard tap *
  page34_i85
#ISCELL
  standard tap *
  page34_i86
#ISCELL
  standard tap *
  page34_i87
#ISCELL
  standard tap *
  page34_i88
#ISCELL
  standard tap *
  page34_i89
#ISCELL
  standard tap *
  page34_i9
#ISCELL
  standard tap *
  page34_i90
#ISCELL
  standard tap *
  page34_i91
#ISCELL
  standard tap *
  page34_i92
#ISCELL
  standard tap *
  page34_i93
#ISCELL
  standard tap *
  page34_i94
#ISCELL
  standard tap *
  page34_i95
#ISCELL
  standard tap *
  page34_i96
#ISCELL
  standard tap *
  page34_i97
#ISCELL
  standard tap *
  page34_i98
#ISCELL
  standard tap *
  page34_i99
